(kicad_pcb
	(version 20260206)
	(generator "pcbnew")
	(generator_version "10.0")
	(general
		(thickness 1.6)
		(legacy_teardrops no)
	)
	(paper "A4")
	(title_block
		(title "04192023_DAF0TMB3IC0_F0TG_MB_C_brd_V02_OCP.brd")
		(comment 1 "Grand Teton / footprints 4930-4933 of 8354")
	)
	(layers
		(0 "F.Cu" signal "TOP")
		(4 "In1.Cu" signal "GND")
		(6 "In2.Cu" signal "IN1")
		(8 "In3.Cu" signal "GND1")
		(10 "In4.Cu" signal "IN2")
		(12 "In5.Cu" signal "GND2")
		(14 "In6.Cu" signal "IN3")
		(16 "In7.Cu" signal "GND3")
		(18 "In8.Cu" signal "VCC")
		(20 "In9.Cu" signal "VCC1")
		(22 "In10.Cu" signal "GND4")
		(24 "In11.Cu" signal "IN4")
		(26 "In12.Cu" signal "GND5")
		(28 "In13.Cu" signal "IN5")
		(30 "In14.Cu" signal "GND6")
		(32 "In15.Cu" signal "IN6")
		(34 "In16.Cu" signal "GND7")
		(2 "B.Cu" signal "BOTTOM")
		(9 "F.Adhes" user "F.Adhesive")
		(11 "B.Adhes" user "B.Adhesive")
		(13 "F.Paste" user "Package Geometry/Pastemask Top")
		(15 "B.Paste" user "Package Geometry/Pastemask Bottom")
		(5 "F.SilkS" user "Ref Des/Silkscreen Top")
		(7 "B.SilkS" user "Ref Des/Silkscreen Bottom")
		(1 "F.Mask" user "Board Geometry/Soldermask Top")
		(3 "B.Mask" user "Board Geometry/Soldermask Bottom")
		(17 "Dwgs.User" user "User.Drawings")
		(19 "Cmts.User" user "User.Comments")
		(21 "Eco1.User" user "User.Eco1")
		(23 "Eco2.User" user "User.Eco2")
		(25 "Edge.Cuts" user "Board Geometry/Outline")
		(27 "Margin" user)
		(31 "F.CrtYd" user "Package Geometry/Place Bound Top")
		(29 "B.CrtYd" user "Package Geometry/Place Bound Bottom")
		(35 "F.Fab" user "Ref Des/Assembly Top")
		(33 "B.Fab" user "Ref Des/Assembly Bottom")
	)
	(footprint ""
		(layer "F.Cu")
		(at 258.275836 -72.976994)
		(property "Reference" "R2114"
			(at 0 0 0)
			(layer "F.SilkS")
			(hide yes)
			(effects
				(font
					(size 1.27 1.27)
				)
			)
		)
		(property "Value" ""
			(at 0 0 0)
			(layer "F.Fab")
			(effects
				(font
					(size 1.27 1.27)
				)
			)
		)
		(duplicate_pad_numbers_are_jumpers no)
		(fp_line
			(start -0.7874 -0.4064)
			(end 0.7874 -0.4064)
			(stroke
				(width 0.1524)
				(type default)
			)
			(layer "F.SilkS")
		)
		(fp_line
			(start -0.7874 0.4064)
			(end -0.7874 -0.4064)
			(stroke
				(width 0.1524)
				(type default)
			)
			(layer "F.SilkS")
		)
		(fp_line
			(start 0.7874 -0.4064)
			(end 0.7874 0.4064)
			(stroke
				(width 0.1524)
				(type default)
			)
			(layer "F.SilkS")
		)
		(fp_line
			(start 0.7874 0.4064)
			(end -0.7874 0.4064)
			(stroke
				(width 0.1524)
				(type default)
			)
			(layer "F.SilkS")
		)
		(fp_line
			(start -0.67945 -0.305054)
			(end -0.12065 -0.305054)
			(stroke
				(width 0.1)
				(type default)
			)
			(layer "F.Fab")
		)
		(fp_line
			(start -0.67945 0.3048)
			(end -0.67945 -0.305054)
			(stroke
				(width 0.1)
				(type default)
			)
			(layer "F.Fab")
		)
		(fp_line
			(start -0.12065 -0.305054)
			(end -0.12065 -0.2794)
			(stroke
				(width 0.1)
				(type default)
			)
			(layer "F.Fab")
		)
		(fp_line
			(start -0.12065 -0.2794)
			(end 0.12065 -0.2794)
			(stroke
				(width 0.1)
				(type default)
			)
			(layer "F.Fab")
		)
		(fp_line
			(start -0.12065 0.2794)
			(end -0.12065 0.3048)
			(stroke
				(width 0.1)
				(type default)
			)
			(layer "F.Fab")
		)
		(fp_line
			(start -0.12065 0.3048)
			(end -0.67945 0.3048)
			(stroke
				(width 0.1)
				(type default)
			)
			(layer "F.Fab")
		)
		(fp_line
			(start 0.120396 0.2794)
			(end -0.12065 0.2794)
			(stroke
				(width 0.1)
				(type default)
			)
			(layer "F.Fab")
		)
		(fp_line
			(start 0.120396 0.3048)
			(end 0.120396 0.2794)
			(stroke
				(width 0.1)
				(type default)
			)
			(layer "F.Fab")
		)
		(fp_line
			(start 0.12065 -0.3048)
			(end 0.67945 -0.3048)
			(stroke
				(width 0.1)
				(type default)
			)
			(layer "F.Fab")
		)
		(fp_line
			(start 0.12065 -0.2794)
			(end 0.12065 -0.3048)
			(stroke
				(width 0.1)
				(type default)
			)
			(layer "F.Fab")
		)
		(fp_line
			(start 0.67945 -0.3048)
			(end 0.67945 0.3048)
			(stroke
				(width 0.1)
				(type default)
			)
			(layer "F.Fab")
		)
		(fp_line
			(start 0.67945 0.3048)
			(end 0.120396 0.3048)
			(stroke
				(width 0.1)
				(type default)
			)
			(layer "F.Fab")
		)
		(pad "1" smd circle
			(at -0.40005 0)
			(size 0 0)
			(layers "F.Cu" "F.Mask" "F.Paste")
			(net "SMB_PCIE_E1S_ISO_EN_R2")
		)
		(pad "2" smd circle
			(at 0.40005 0)
			(size 0 0)
			(layers "F.Cu" "F.Mask" "F.Paste")
			(net "SMB_PCIE_E1S_ISO_EN")
		)
	)
	(footprint ""
		(layer "F.Cu")
		(at 52.705 -38.735)
		(property "Reference" "U31"
			(at -0.882142 -2.608072 0)
			(unlocked yes)
			(layer "F.SilkS")
			(effects
				(font
					(size 0.7874 0.5842)
					(thickness 0.1524)
				)
				(justify left)
			)
		)
		(property "Value" ""
			(at 0 0 0)
			(layer "F.Fab")
			(effects
				(font
					(size 1.27 1.27)
				)
			)
		)
		(duplicate_pad_numbers_are_jumpers no)
		(fp_line
			(start -1.733296 -1.549908)
			(end -1.733296 1.549908)
			(stroke
				(width 0.1524)
				(type default)
			)
			(layer "F.SilkS")
		)
		(fp_line
			(start -1.733296 1.549908)
			(end 1.733296 1.549908)
			(stroke
				(width 0.1524)
				(type default)
			)
			(layer "F.SilkS")
		)
		(fp_line
			(start -0.660908 -1.549908)
			(end -1.733296 -1.549908)
			(stroke
				(width 0.1524)
				(type default)
			)
			(layer "F.SilkS")
		)
		(fp_line
			(start 0 -0.889)
			(end -0.660908 -1.549908)
			(stroke
				(width 0.1524)
				(type default)
			)
			(layer "F.SilkS")
		)
		(fp_line
			(start 0.660908 -1.549908)
			(end 0 -0.889)
			(stroke
				(width 0.1524)
				(type default)
			)
			(layer "F.SilkS")
		)
		(fp_line
			(start 1.733296 -1.549908)
			(end 0.660908 -1.549908)
			(stroke
				(width 0.1524)
				(type default)
			)
			(layer "F.SilkS")
		)
		(fp_line
			(start 1.733296 1.549908)
			(end 1.733296 -1.549908)
			(stroke
				(width 0.1524)
				(type default)
			)
			(layer "F.SilkS")
		)
		(fp_poly
			(pts
				(xy -1.556512 -2.49555) (xy -2.005076 -2.257298) (xy -1.542542 -1.92786)
			)
			(stroke
				(width 0)
				(type default)
			)
			(fill yes)
			(layer "F.SilkS")
		)
		(fp_line
			(start -0.849884 -1.549908)
			(end -0.849884 1.549908)
			(stroke
				(width 0.1)
				(type default)
			)
			(layer "F.Fab")
		)
		(fp_line
			(start -0.849884 1.549908)
			(end 0.849884 1.549908)
			(stroke
				(width 0.1)
				(type default)
			)
			(layer "F.Fab")
		)
		(fp_line
			(start 0.849884 -1.549908)
			(end -0.849884 -1.549908)
			(stroke
				(width 0.1)
				(type default)
			)
			(layer "F.Fab")
		)
		(fp_line
			(start 0.849884 1.549908)
			(end 0.849884 -1.549908)
			(stroke
				(width 0.1)
				(type default)
			)
			(layer "F.Fab")
		)
		(fp_poly
			(pts
				(xy -2.4384 -1.20396) (xy -2.4384 -0.69596) (xy -1.9304 -0.94996)
			)
			(stroke
				(width 0)
				(type default)
			)
			(fill yes)
			(layer "F.Fab")
		)
		(pad "1" smd rect
			(at -1.199896 -0.94996 270)
			(size 0.5588 0.8128)
			(layers "F.Cu" "F.Mask" "F.Paste")
			(net "P12V_OCP_V3_2_EN_R3")
		)
		(pad "2" smd rect
			(at -1.199896 0 270)
			(size 0.5588 0.8128)
			(layers "F.Cu" "F.Mask" "F.Paste")
			(net "HP_LVC3_OCP_V3_2_PRSNT2")
		)
		(pad "3" smd rect
			(at -1.199896 0.94996 270)
			(size 0.5588 0.8128)
			(layers "F.Cu" "F.Mask" "F.Paste")
			(net "GND")
		)
		(pad "4" smd rect
			(at 1.199896 0.94996 270)
			(size 0.5588 0.8128)
			(layers "F.Cu" "F.Mask" "F.Paste")
			(net "P12V_OCP_V3_2_BUF_EN")
		)
		(pad "5" smd rect
			(at 1.199896 -0.94996 270)
			(size 0.5588 0.8128)
			(layers "F.Cu" "F.Mask" "F.Paste")
			(net "P3V3_AUX")
		)
	)
	(footprint ""
		(layer "F.Cu")
		(at 366.06734 -385.23926 180)
		(property "Reference" "C898"
			(at 0 0 180)
			(layer "F.SilkS")
			(hide yes)
			(effects
				(font
					(size 1.27 1.27)
				)
			)
		)
		(property "Value" ""
			(at 0 0 180)
			(layer "F.Fab")
			(effects
				(font
					(size 1.27 1.27)
				)
			)
		)
		(duplicate_pad_numbers_are_jumpers no)
		(fp_line
			(start 0.299974 0.150114)
			(end -0.299974 0.150114)
			(stroke
				(width 0.1)
				(type default)
			)
			(layer "F.Fab")
		)
		(fp_line
			(start 0.299974 -0.150114)
			(end 0.299974 0.150114)
			(stroke
				(width 0.1)
				(type default)
			)
			(layer "F.Fab")
		)
		(fp_line
			(start -0.299974 0.150114)
			(end -0.299974 -0.150114)
			(stroke
				(width 0.1)
				(type default)
			)
			(layer "F.Fab")
		)
		(fp_line
			(start -0.299974 -0.150114)
			(end 0.299974 -0.150114)
			(stroke
				(width 0.1)
				(type default)
			)
			(layer "F.Fab")
		)
		(pad "1" smd rect
			(at -0.2667 0 180)
			(size 0.3048 0.381)
			(layers "F.Cu" "F.Mask" "F.Paste")
			(net "P5E_CPU0_P3_TX_C_DN<1>")
		)
		(pad "2" smd rect
			(at 0.2667 0 180)
			(size 0.3048 0.381)
			(layers "F.Cu" "F.Mask" "F.Paste")
			(net "P5E_CPU0_P3_TX_DN<1>")
		)
	)
	(footprint ""
		(layer "F.Cu")
		(at 33.291272 -434.173884)
		(property "Reference" "C1766"
			(at 0 0 0)
			(layer "F.SilkS")
			(hide yes)
			(effects
				(font
					(size 1.27 1.27)
				)
			)
		)
		(property "Value" ""
			(at 0 0 0)
			(layer "F.Fab")
			(effects
				(font
					(size 1.27 1.27)
				)
			)
		)
		(duplicate_pad_numbers_are_jumpers no)
		(fp_line
			(start -0.7874 -0.4064)
			(end 0.7874 -0.4064)
			(stroke
				(width 0.1524)
				(type default)
			)
			(layer "F.SilkS")
		)
		(fp_line
			(start -0.7874 0.4064)
			(end -0.7874 -0.4064)
			(stroke
				(width 0.1524)
				(type default)
			)
			(layer "F.SilkS")
		)
		(fp_line
			(start 0.7874 -0.4064)
			(end 0.7874 0.4064)
			(stroke
				(width 0.1524)
				(type default)
			)
			(layer "F.SilkS")
		)
		(fp_line
			(start 0.7874 0.4064)
			(end -0.7874 0.4064)
			(stroke
				(width 0.1524)
				(type default)
			)
			(layer "F.SilkS")
		)
		(fp_line
			(start -0.67945 -0.305054)
			(end -0.12065 -0.305054)
			(stroke
				(width 0.1)
				(type default)
			)
			(layer "F.Fab")
		)
		(fp_line
			(start -0.67945 0.3048)
			(end -0.67945 -0.305054)
			(stroke
				(width 0.1)
				(type default)
			)
			(layer "F.Fab")
		)
		(fp_line
			(start -0.12065 -0.305054)
			(end -0.12065 -0.2794)
			(stroke
				(width 0.1)
				(type default)
			)
			(layer "F.Fab")
		)
		(fp_line
			(start -0.12065 -0.2794)
			(end 0.12065 -0.2794)
			(stroke
				(width 0.1)
				(type default)
			)
			(layer "F.Fab")
		)
		(fp_line
			(start -0.12065 0.2794)
			(end -0.12065 0.3048)
			(stroke
				(width 0.1)
				(type default)
			)
			(layer "F.Fab")
		)
		(fp_line
			(start -0.12065 0.3048)
			(end -0.67945 0.3048)
			(stroke
				(width 0.1)
				(type default)
			)
			(layer "F.Fab")
		)
		(fp_line
			(start 0.120396 0.2794)
			(end -0.12065 0.2794)
			(stroke
				(width 0.1)
				(type default)
			)
			(layer "F.Fab")
		)
		(fp_line
			(start 0.120396 0.3048)
			(end 0.120396 0.2794)
			(stroke
				(width 0.1)
				(type default)
			)
			(layer "F.Fab")
		)
		(fp_line
			(start 0.12065 -0.3048)
			(end 0.67945 -0.3048)
			(stroke
				(width 0.1)
				(type default)
			)
			(layer "F.Fab")
		)
		(fp_line
			(start 0.12065 -0.2794)
			(end 0.12065 -0.3048)
			(stroke
				(width 0.1)
				(type default)
			)
			(layer "F.Fab")
		)
		(fp_line
			(start 0.67945 -0.3048)
			(end 0.67945 0.3048)
			(stroke
				(width 0.1)
				(type default)
			)
			(layer "F.Fab")
		)
		(fp_line
			(start 0.67945 0.3048)
			(end 0.120396 0.3048)
			(stroke
				(width 0.1)
				(type default)
			)
			(layer "F.Fab")
		)
		(pad "1" smd circle
			(at -0.40005 0)
			(size 0 0)
			(layers "F.Cu" "F.Mask" "F.Paste")
			(net "P3V3_AUX")
		)
		(pad "2" smd circle
			(at 0.40005 0)
			(size 0 0)
			(layers "F.Cu" "F.Mask" "F.Paste")
			(net "GND")
		)
	)
)
